# S9S_MB_2U (Grand Teton) — schematic netlist excerpt (pin names and nets, part order shuffled) for the footprints in the layout excerpt that follows; sources: Cadence DE-HDL packaged netlist, KiCad conversion of 03242023_DA0F0TMBIJ0_F0T_Motherboard_J_brd_V01_OCP.brd

C872  Q_CAP_DIFFBUS  DIFF BUS_0.22UF 6.3V 20% X6S  pkg C0201  page 174 : \1\ = P5E_CPU0_PE3_TX_C_DN<14> ; \2\ = P5E_CPU0_PE3_TX_DN<14>
C223  Q_CAP  10UF 6.3V 20% X6S  pkg C0402  page 77 : A = PVCCIN_CPU1 ; B = GND
PC479  Q_CAP  2.2UF 10V 10% X6S  pkg C0402  page 288 : A = PVCCIN_CPU1_VDD8 ; B = GND

(kicad_pcb
	(version 20260206)
	(generator "pcbnew")
	(generator_version "10.0")
	(general
		(thickness 1.6)
		(legacy_teardrops no)
	)
	(paper "A4")
	(title_block
		(title "03242023_DA0F0TMBIJ0_F0T_Motherboard_J_brd_V01_OCP.brd")
		(comment 1 "Grand Teton / footprints 2098-2100 of 6105")
	)
	(layers
		(0 "F.Cu" signal "TOP")
		(4 "In1.Cu" signal "GND")
		(6 "In2.Cu" signal "IN1")
		(8 "In3.Cu" signal "GND1")
		(10 "In4.Cu" signal "IN2")
		(12 "In5.Cu" signal "GND2")
		(14 "In6.Cu" signal "IN3")
		(16 "In7.Cu" signal "GND3")
		(18 "In8.Cu" signal "VCC")
		(20 "In9.Cu" signal "VCC1")
		(22 "In10.Cu" signal "GND4")
		(24 "In11.Cu" signal "IN4")
		(26 "In12.Cu" signal "GND5")
		(28 "In13.Cu" signal "IN5")
		(30 "In14.Cu" signal "GND6")
		(32 "In15.Cu" signal "IN6")
		(34 "In16.Cu" signal "GND7")
		(2 "B.Cu" signal "BOTTOM")
		(9 "F.Adhes" user "F.Adhesive")
		(11 "B.Adhes" user "B.Adhesive")
		(13 "F.Paste" user "Package Geometry/Pastemask Top")
		(15 "B.Paste" user "Package Geometry/Pastemask Bottom")
		(5 "F.SilkS" user "Ref Des/Silkscreen Top")
		(7 "B.SilkS" user "Ref Des/Silkscreen Bottom")
		(1 "F.Mask" user "Board Geometry/Soldermask Top")
		(3 "B.Mask" user "Board Geometry/Soldermask Bottom")
		(17 "Dwgs.User" user "User.Drawings")
		(19 "Cmts.User" user "User.Comments")
		(21 "Eco1.User" user "User.Eco1")
		(23 "Eco2.User" user "User.Eco2")
		(25 "Edge.Cuts" user "Board Geometry/Outline")
		(27 "Margin" user)
		(31 "F.CrtYd" user "Package Geometry/Place Bound Top")
		(29 "B.CrtYd" user "Package Geometry/Place Bound Bottom")
		(35 "F.Fab" user "Ref Des/Assembly Top")
		(33 "B.Fab" user "Ref Des/Assembly Bottom")
	)
	(footprint ""
		(layer "F.Cu")
		(at 117.526816 -240.277142 90)
		(property "Reference" "C223"
			(at 0 0 90)
			(layer "F.SilkS")
			(hide yes)
			(effects
				(font
					(size 1.27 1.27)
				)
			)
		)
		(property "Value" ""
			(at 0 0 90)
			(layer "F.Fab")
			(effects
				(font
					(size 1.27 1.27)
				)
			)
		)
		(duplicate_pad_numbers_are_jumpers no)
		(fp_line
			(start 0.7874 -0.4064)
			(end 0.7874 0.4064)
			(stroke
				(width 0.1524)
				(type default)
			)
			(layer "F.SilkS")
		)
		(fp_line
			(start -0.7874 -0.4064)
			(end 0.7874 -0.4064)
			(stroke
				(width 0.1524)
				(type default)
			)
			(layer "F.SilkS")
		)
		(fp_line
			(start 0.7874 0.4064)
			(end -0.7874 0.4064)
			(stroke
				(width 0.1524)
				(type default)
			)
			(layer "F.SilkS")
		)
		(fp_line
			(start -0.7874 0.4064)
			(end -0.7874 -0.4064)
			(stroke
				(width 0.1524)
				(type default)
			)
			(layer "F.SilkS")
		)
		(fp_line
			(start -0.12065 -0.305054)
			(end -0.12065 -0.2794)
			(stroke
				(width 0.1)
				(type default)
			)
			(layer "F.Fab")
		)
		(fp_line
			(start -0.67945 -0.305054)
			(end -0.12065 -0.305054)
			(stroke
				(width 0.1)
				(type default)
			)
			(layer "F.Fab")
		)
		(fp_line
			(start 0.67945 -0.3048)
			(end 0.67945 0.3048)
			(stroke
				(width 0.1)
				(type default)
			)
			(layer "F.Fab")
		)
		(fp_line
			(start 0.12065 -0.3048)
			(end 0.67945 -0.3048)
			(stroke
				(width 0.1)
				(type default)
			)
			(layer "F.Fab")
		)
		(fp_line
			(start 0.12065 -0.2794)
			(end 0.12065 -0.3048)
			(stroke
				(width 0.1)
				(type default)
			)
			(layer "F.Fab")
		)
		(fp_line
			(start -0.12065 -0.2794)
			(end 0.12065 -0.2794)
			(stroke
				(width 0.1)
				(type default)
			)
			(layer "F.Fab")
		)
		(fp_line
			(start 0.120396 0.2794)
			(end -0.12065 0.2794)
			(stroke
				(width 0.1)
				(type default)
			)
			(layer "F.Fab")
		)
		(fp_line
			(start -0.12065 0.2794)
			(end -0.12065 0.3048)
			(stroke
				(width 0.1)
				(type default)
			)
			(layer "F.Fab")
		)
		(fp_line
			(start 0.67945 0.3048)
			(end 0.120396 0.3048)
			(stroke
				(width 0.1)
				(type default)
			)
			(layer "F.Fab")
		)
		(fp_line
			(start 0.120396 0.3048)
			(end 0.120396 0.2794)
			(stroke
				(width 0.1)
				(type default)
			)
			(layer "F.Fab")
		)
		(fp_line
			(start -0.12065 0.3048)
			(end -0.67945 0.3048)
			(stroke
				(width 0.1)
				(type default)
			)
			(layer "F.Fab")
		)
		(fp_line
			(start -0.67945 0.3048)
			(end -0.67945 -0.305054)
			(stroke
				(width 0.1)
				(type default)
			)
			(layer "F.Fab")
		)
		(pad "1" smd circle
			(at -0.40005 0 90)
			(size 0 0)
			(layers "F.Cu" "F.Mask" "F.Paste")
			(net "PVCCIN_CPU1")
		)
		(pad "2" smd circle
			(at 0.40005 0 90)
			(size 0 0)
			(layers "F.Cu" "F.Mask" "F.Paste")
			(net "GND")
		)
	)
	(footprint ""
		(layer "F.Cu")
		(at 375.80697 -408.517344 -90)
		(property "Reference" "C872"
			(at 0 0 270)
			(layer "F.SilkS")
			(hide yes)
			(effects
				(font
					(size 1.27 1.27)
				)
			)
		)
		(property "Value" ""
			(at 0 0 270)
			(layer "F.Fab")
			(effects
				(font
					(size 1.27 1.27)
				)
			)
		)
		(duplicate_pad_numbers_are_jumpers no)
		(fp_line
			(start -0.299974 0.150114)
			(end -0.299974 -0.150114)
			(stroke
				(width 0.1)
				(type default)
			)
			(layer "F.Fab")
		)
		(fp_line
			(start 0.299974 0.150114)
			(end -0.299974 0.150114)
			(stroke
				(width 0.1)
				(type default)
			)
			(layer "F.Fab")
		)
		(fp_line
			(start -0.299974 -0.150114)
			(end 0.299974 -0.150114)
			(stroke
				(width 0.1)
				(type default)
			)
			(layer "F.Fab")
		)
		(fp_line
			(start 0.299974 -0.150114)
			(end 0.299974 0.150114)
			(stroke
				(width 0.1)
				(type default)
			)
			(layer "F.Fab")
		)
		(pad "1" smd rect
			(at -0.2667 0 270)
			(size 0.3048 0.381)
			(layers "F.Cu" "F.Mask" "F.Paste")
			(net "P5E_CPU0_PE3_TX_C_DN<14>")
		)
		(pad "2" smd rect
			(at 0.2667 0 270)
			(size 0.3048 0.381)
			(layers "F.Cu" "F.Mask" "F.Paste")
			(net "P5E_CPU0_PE3_TX_DN<14>")
		)
	)
	(footprint ""
		(layer "F.Cu")
		(at 134.225538 -345.393264 90)
		(property "Reference" "PC479"
			(at 0 0 90)
			(layer "F.SilkS")
			(hide yes)
			(effects
				(font
					(size 1.27 1.27)
				)
			)
		)
		(property "Value" ""
			(at 0 0 90)
			(layer "F.Fab")
			(effects
				(font
					(size 1.27 1.27)
				)
			)
		)
		(duplicate_pad_numbers_are_jumpers no)
		(fp_line
			(start 0.7874 -0.4064)
			(end 0.7874 0.4064)
			(stroke
				(width 0.1524)
				(type default)
			)
			(layer "F.SilkS")
		)
		(fp_line
			(start -0.7874 -0.4064)
			(end 0.7874 -0.4064)
			(stroke
				(width 0.1524)
				(type default)
			)
			(layer "F.SilkS")
		)
		(fp_line
			(start 0.7874 0.4064)
			(end -0.7874 0.4064)
			(stroke
				(width 0.1524)
				(type default)
			)
			(layer "F.SilkS")
		)
		(fp_line
			(start -0.7874 0.4064)
			(end -0.7874 -0.4064)
			(stroke
				(width 0.1524)
				(type default)
			)
			(layer "F.SilkS")
		)
		(fp_line
			(start -0.12065 -0.305054)
			(end -0.12065 -0.2794)
			(stroke
				(width 0.1)
				(type default)
			)
			(layer "F.Fab")
		)
		(fp_line
			(start -0.67945 -0.305054)
			(end -0.12065 -0.305054)
			(stroke
				(width 0.1)
				(type default)
			)
			(layer "F.Fab")
		)
		(fp_line
			(start 0.67945 -0.3048)
			(end 0.67945 0.3048)
			(stroke
				(width 0.1)
				(type default)
			)
			(layer "F.Fab")
		)
		(fp_line
			(start 0.12065 -0.3048)
			(end 0.67945 -0.3048)
			(stroke
				(width 0.1)
				(type default)
			)
			(layer "F.Fab")
		)
		(fp_line
			(start 0.12065 -0.2794)
			(end 0.12065 -0.3048)
			(stroke
				(width 0.1)
				(type default)
			)
			(layer "F.Fab")
		)
		(fp_line
			(start -0.12065 -0.2794)
			(end 0.12065 -0.2794)
			(stroke
				(width 0.1)
				(type default)
			)
			(layer "F.Fab")
		)
		(fp_line
			(start 0.120396 0.2794)
			(end -0.12065 0.2794)
			(stroke
				(width 0.1)
				(type default)
			)
			(layer "F.Fab")
		)
		(fp_line
			(start -0.12065 0.2794)
			(end -0.12065 0.3048)
			(stroke
				(width 0.1)
				(type default)
			)
			(layer "F.Fab")
		)
		(fp_line
			(start 0.67945 0.3048)
			(end 0.120396 0.3048)
			(stroke
				(width 0.1)
				(type default)
			)
			(layer "F.Fab")
		)
		(fp_line
			(start 0.120396 0.3048)
			(end 0.120396 0.2794)
			(stroke
				(width 0.1)
				(type default)
			)
			(layer "F.Fab")
		)
		(fp_line
			(start -0.12065 0.3048)
			(end -0.67945 0.3048)
			(stroke
				(width 0.1)
				(type default)
			)
			(layer "F.Fab")
		)
		(fp_line
			(start -0.67945 0.3048)
			(end -0.67945 -0.305054)
			(stroke
				(width 0.1)
				(type default)
			)
			(layer "F.Fab")
		)
		(pad "1" smd circle
			(at -0.40005 0 90)
			(size 0 0)
			(layers "F.Cu" "F.Mask" "F.Paste")
			(net "PVCCIN_CPU1_VDD8")
		)
		(pad "2" smd circle
			(at 0.40005 0 90)
			(size 0 0)
			(layers "F.Cu" "F.Mask" "F.Paste")
			(net "GND")
		)
	)
)
